# S9S_MB_2U (Grand Teton) — schematic parts with pin connectivity, parts 3141–3158 of 6093; source: Cadence DE-HDL packaged netlist (pstxprt.dat, pstxnet.dat, pstchip.dat)

PU202  MAX15090BEWIT  MAX15090BEWI+T IC  pkg BGA28_0-5_3-525X2-065  page 156
  A1  ISENSE  OUT  = P3V3_OCP_SENSE_1
  A2  VCC  POWER  = P3V3_OCP_VCC_1
  A3  IN_A3  IN  = P3V3_AUX
  A4  OUT_A4  OUT  = P3V3_OCP_SFF_R
  A5  IN_A5  IN  = P3V3_AUX
  A6  GATE  BI  = P3V3_OCP_GATE_PU202_1
  A7  CDLY  IN  = GND
  B1  CB  BI  = P3V3_OCP_CB_1
  B2  GND_B2  POWER  = GND
  B3  IN_B3  IN  = P3V3_AUX
  B4  OUT_B4  OUT  = P3V3_OCP_SFF_R
  B5  IN_B5  IN  = P3V3_AUX
  B6  OUT_B6  OUT  = P3V3_OCP_SFF_R
  B7  \en#\  IN  = GND
  C1  GND_C1  POWER  = GND
  C2  GND_C2  POWER  = GND
  C3  IN_C3  IN  = P3V3_AUX
  C4  OUT_C4  OUT  = P3V3_OCP_SFF_R
  C5  IN_C5  IN  = P3V3_AUX
  C6  OUT_C6  OUT  = P3V3_OCP_SFF_R
  C7  \fault#\  OUT  = P3V3_OCP_FAULT_1
  D1  REG  OUT  = P3V3_OCP_REG_1
  D2  UV  IN  = P3V3_OCP_UV_1
  D3  OV  IN  = P3V3_OCP_OV_1
  D4  OUT_D4  OUT  = P3V3_OCP_SFF_R
  D5  IN_D5  IN  = P3V3_AUX
  D6  OUT_D6  OUT  = P3V3_OCP_SFF_R
  D7  PG  OUT  = P3V3_OCP_PWRGD_1

PU203  MAX15090BEWIT  MAX15090BEWI+T EMPTY  pkg BGA28_0-5_3-525X2-065  page 156
  A1  ISENSE  OUT  = P12V_OCP_SENSE_1
  A2  VCC  POWER  = P12V_OCP_VCC_1
  A3  IN_A3  IN  = P12V_AUX
  A4  OUT_A4  OUT  = P12V_OCP_SFF
  A5  IN_A5  IN  = P12V_AUX
  A6  GATE  BI  = P12V_OCP_GATE_1
  A7  CDLY  IN  = GND
  B1  CB  BI  = P12V_OCP_CB_1
  B2  GND_B2  POWER  = GND
  B3  IN_B3  IN  = P12V_AUX
  B4  OUT_B4  OUT  = P12V_OCP_SFF
  B5  IN_B5  IN  = P12V_AUX
  B6  OUT_B6  OUT  = P12V_OCP_SFF
  B7  \en#\  IN  = GND
  C1  GND_C1  POWER  = GND
  C2  GND_C2  POWER  = GND
  C3  IN_C3  IN  = P12V_AUX
  C4  OUT_C4  OUT  = P12V_OCP_SFF
  C5  IN_C5  IN  = P12V_AUX
  C6  OUT_C6  OUT  = P12V_OCP_SFF
  C7  \fault#\  OUT  = P12V_OCP_FAULT_1
  D1  REG  OUT  = P12V_OCP_REG_1
  D2  UV  IN  = P12V_OCP_UV_1
  D3  OV  IN  = P12V_OCP_OV_1
  D4  OUT_D4  OUT  = P12V_OCP_SFF
  D5  IN_D5  IN  = P12V_AUX
  D6  OUT_D6  OUT  = P12V_OCP_SFF
  D7  PG  OUT  = P12V_OCP_PWRGD_1

PU204  RS31312R  IC  pkg QFN22_TH_3X5  page 157
  1  EN  IN  = P12V_OCP_EN_1_R2
  2  LOADEN  IN  = GND
  3  ENTM  IN  = GND
  4  TIMER  IN  = P12V_OCP_TIMER_1
  5  ISET  IN  = P12V_OCP_ISET_1
  6  SS  IN  = P12V_OCP_SS_1
  7  GND  POWER  = GND
  8  IMON  OUT  = P12V_OCP_IMON_1
  9  FLTB  OUT  = P12V_OCP_FLTB_1
  10  PG  OUT  = HP_LVC3_OCP_V3_1_P12V_PWRGD
  11  OV  IN  = P12V_OCP_OV_FB_1
  12  AVIN  IN  = P12V_OCP_AVIN_PD_1
  13  VOUT_13  OUT  = P12V_OCP_SFF
  14  VOUT_14  OUT  = P12V_OCP_SFF
  15  VOUT_15  OUT  = P12V_OCP_SFF
  16  VOUT_16  OUT  = P12V_OCP_SFF
  17  VOUT_17  OUT  = P12V_OCP_SFF
  18  VOUT_18  OUT  = P12V_OCP_SFF
  19  VOUT_19  OUT  = P12V_OCP_SFF
  20  VOUT_20  OUT  = P12V_OCP_SFF
  21_22  VIN_21_22  IN  = P12V_AUX
  23  VIN_23  IN  = P12V_AUX
  24  VIN_24  IN  = P12V_AUX
  25  VIN_25  IN  = P12V_AUX
  26  VIN_26  IN  = P12V_AUX

PU205  MP5016GQHLZ  MP5016GQH-L-Z EMPTY  pkg QFN8_2X1-5  page 157
  1_2  VCC  POWER  = P3V3_AUX
  3  GND  POWER  = GND
  4  ILIMIT  OUT  = P3V3_OCP_ILIMIT_1
  5  MODE  IN  = P3V3_OCP_MODE_1
  6_7  SOURCE  OUT  = P3V3_OCP_SFF_R
  8  GATE  OUT  = P3V3_OCP_GATE_1
  9  EN  IN  = P3V3_OCP_EN_1_R2
  10  DV_DT  OUT  = P3V3_OCP_DVDT_1

PU206  RS31312R  IC  pkg QFN22_TH_3X5  page 163
  1  EN  IN  = P12V_OCP_V3_2_EN_2_R3
  2  LOADEN  IN  = GND
  3  ENTM  IN  = GND
  4  TIMER  IN  = P12V_OCP_TIMER_2
  5  ISET  IN  = P12V_OCP_ISET_2
  6  SS  IN  = P12V_OCP_SS_2
  7  GND  POWER  = GND
  8  IMON  OUT  = P12V_OCP_IMON_2
  9  FLTB  OUT  = P12V_OCP_FLTB_2
  10  PG  OUT  = HP_LVC3_OCP_V3_2_P12V_PWRGD
  11  OV  IN  = P12V_OCP_OV_FB_2
  12  AVIN  IN  = P12V_OCP_AVIN_PD_2
  13  VOUT_13  OUT  = P12V_OCP_V3_2
  14  VOUT_14  OUT  = P12V_OCP_V3_2
  15  VOUT_15  OUT  = P12V_OCP_V3_2
  16  VOUT_16  OUT  = P12V_OCP_V3_2
  17  VOUT_17  OUT  = P12V_OCP_V3_2
  18  VOUT_18  OUT  = P12V_OCP_V3_2
  19  VOUT_19  OUT  = P12V_OCP_V3_2
  20  VOUT_20  OUT  = P12V_OCP_V3_2
  21_22  VIN_21_22  IN  = P12V_AUX
  23  VIN_23  IN  = P12V_AUX
  24  VIN_24  IN  = P12V_AUX
  25  VIN_25  IN  = P12V_AUX
  26  VIN_26  IN  = P12V_AUX

PU207  MP5016GQHLZ  MP5016GQH-L-Z EMPTY  pkg QFN8_2X1-5  page 163
  1_2  VCC  POWER  = P3V3_AUX
  3  GND  POWER  = GND
  4  ILIMIT  OUT  = P3V3_OCP_ILIMIT_2
  5  MODE  IN  = P3V3_OCP_MODE_2
  6_7  SOURCE  OUT  = P3V3_OCP_V3_2_R
  8  GATE  OUT  = P3V3_OCP_GATE_PU207_2
  9  EN  IN  = P3V3_OCP_EN_2
  10  DV_DT  OUT  = P3V3_OCP_DVDT_2

PU287  MP5991GLUZ  MP5991GLU-Z IC  pkg LGA32_TH_0-5_5X5  page 302
  1  VOUT1  OUT  = P12V_AUX
  2  VOUT2  OUT  = P12V_AUX
  3  D_OC  OUT  = HSC_D_OC_1
  4  \on\  IN  = HSC_ON
  5  GOK  OUT  = HSC_FAULT
  6  FLT_TYPE  IN  = HSC_FLT_TYPE_1
  7  NC1  TRI  = HSC_NC1_1
  8  MODE  IN  = HSC_MODE_1
  9  VIN1  IN  = P12V_PSU
  10  VIN2  IN  = P12V_PSU
  11  VIN3  IN  = P12V_PSU
  12  VIN4  IN  = P12V_PSU
  13  VIN5  IN  = P12V_PSU
  14  VIN6  IN  = P12V_PSU
  15  VIN7  IN  = P12V_PSU
  16  VIN8  IN  = P12V_PSU
  17  SCREF_OCWREF  IN  = HSC_SCREF_1
  18  VTEMP  OUT  = HSC_VTEMP
  19  SS  IN  = HSC_SS
  20  GND  POWER  = AGND_HSC
  21  VDD33  POWER  = HSC_VDD_R_1
  22  IMON  OUT  = HSC_IMON
  23  CS  OUT  = HSC_CS_1
  24  OCREF  OUT  = HSC_OCREF
  25  VOUT3  OUT  = P12V_AUX
  26  VOUT4  OUT  = P12V_AUX
  27  VOUT5  OUT  = P12V_AUX
  28  VOUT6  OUT  = P12V_AUX
  29  VOUT7  OUT  = P12V_AUX
  30  VOUT8  OUT  = P12V_AUX
  31  VOUT9  OUT  = P12V_AUX
  32  VOUT10  OUT  = P12V_AUX
  33  VIN9  IN  = P12V_PSU

PU288  MP5991GLUZ  MP5991GLU-Z IC  pkg LGA32_TH_0-5_5X5  page 302
  1  VOUT1  OUT  = P12V_AUX
  2  VOUT2  OUT  = P12V_AUX
  3  D_OC  OUT  = HSC_D_OC_2
  4  \on\  IN  = HSC_ON
  5  GOK  OUT  = HSC_FAULT
  6  FLT_TYPE  IN  = HSC_FLT_TYPE_2
  7  NC1  TRI  = HSC_NC1_2
  8  MODE  IN  = HSC_MODE_2
  9  VIN1  IN  = P12V_PSU
  10  VIN2  IN  = P12V_PSU
  11  VIN3  IN  = P12V_PSU
  12  VIN4  IN  = P12V_PSU
  13  VIN5  IN  = P12V_PSU
  14  VIN6  IN  = P12V_PSU
  15  VIN7  IN  = P12V_PSU
  16  VIN8  IN  = P12V_PSU
  17  SCREF_OCWREF  IN  = HSC_SCREF_2
  18  VTEMP  OUT  = HSC_VTEMP
  19  SS  IN  = HSC_SS
  20  GND  POWER  = AGND_HSC
  21  VDD33  POWER  = HSC_VDD_R_2
  22  IMON  OUT  = HSC_IMON
  23  CS  OUT  = HSC_CS_2
  24  OCREF  OUT  = HSC_OCREF
  25  VOUT3  OUT  = P12V_AUX
  26  VOUT4  OUT  = P12V_AUX
  27  VOUT5  OUT  = P12V_AUX
  28  VOUT6  OUT  = P12V_AUX
  29  VOUT7  OUT  = P12V_AUX
  30  VOUT8  OUT  = P12V_AUX
  31  VOUT9  OUT  = P12V_AUX
  32  VOUT10  OUT  = P12V_AUX
  33  VIN9  IN  = P12V_PSU

PU289  MP5990GMA1111Z  MP5990GMA-1111-Z IC  pkg LGA45_TH_0-45_7X5  page 301
  1  VIN1  IN  = P12V_PSU
  2  VIN2  IN  = P12V_PSU
  3  VIN3  IN  = P12V_PSU
  4  VIN4  IN  = P12V_PSU
  5  VIN5  IN  = P12V_PSU
  6  VIN6  IN  = P12V_PSU
  7  VIN7  IN  = P12V_PSU
  8  VIN8  IN  = P12V_PSU
  9  VINSEN  IN  = HSC_VSENSE
  10  \alt#\  OUT  = IRQ_SML1_PMBUS_ALERT
  11  SCL  IN  = SMB_SML1_PMBUS_HSC_L_SCL
  12  SDA  BI  = SMB_SML1_PMBUS_HSC_R_SDA
  13  \pg||ocw#\  OUT  = MB0_P12V_STBY_PWRGD
  14  \vin_uvw#\  OUT  = HSC_VIN_UVW_N
  15  VTEMP  IN  = HSC_VTEMP
  16  SS  OUT  = HSC_SS
  17  VDD33_1  POWER  = HSC_VDD_R
  18  GND1  POWER  = AGND_HSC
  19  VDD18  POWER  = HSC_VDD18
  20  CS  OUT  = HSC_CS
  21  IMON  BI  = HSC_IMON
  22  OCREF  OUT  = HSC_OCREF
  23  ADDR  IN  = HSC_ADDR
  24  VOSEN  IN  = HSC_VOSEN
  25  SCREF_OCWREF  OUT  = HSC_SCREF
  26  EN  IN  = HSC_EN_R
  27  VOUT1  OUT  = P12V_AUX
  28  VOUT2  OUT  = P12V_AUX
  29  VOUT3  OUT  = P12V_AUX
  30  VOUT4  OUT  = P12V_AUX
  31  VOUT5  OUT  = P12V_AUX
  32  VOUT6  OUT  = P12V_AUX
  33  VOUT7  OUT  = P12V_AUX
  34  VOUT8  OUT  = P12V_AUX
  35  VOUT9  OUT  = P12V_AUX
  36  VOUT10  OUT  = P12V_AUX
  37  D_OC  OUT  = HSC_D_OC_R
  38  \on\  OUT  = HSC_ON_R
  39  GOK  BI  = HSC_FAULT
  40  FLT_TYPE  IN  = HSC_FLT_TYPE
  41  MODE  IN  = HSC_MODE
  42  VIN9  IN  = P12V_PSU
  43  VIN10  IN  = P12V_PSU
  44  GND2  POWER  = AGND_HSC
  45  VDD33_2  POWER  = HSC_VDD_R

PU292  RS31312R  IC  pkg QFN22_TH_3X5  page 193
  1  EN  IN  = P12V_E1S_EN_0_R2
  2  LOADEN  IN  = GND
  3  ENTM  IN  = GND
  4  TIMER  IN  = P12V_E1S_TIMER_0
  5  ISET  IN  = P12V_E1S_ISET_0
  6  SS  IN  = P12V_E1S_SS_0
  7  GND  POWER  = GND
  8  IMON  OUT  = P12V_E1S_IMON_0
  9  FLTB  OUT  = P12V_E1S_FLTB_0
  10  PG  OUT  = HP_LVC3_E1S_0_HSC_PWRGD
  11  OV  IN  = P12V_E1S_OV_FB_0
  12  AVIN  IN  = P12V_E1S_AVIN_PD_0
  13  VOUT_13  OUT  = P12V_E1S_0
  14  VOUT_14  OUT  = P12V_E1S_0
  15  VOUT_15  OUT  = P12V_E1S_0
  16  VOUT_16  OUT  = P12V_E1S_0
  17  VOUT_17  OUT  = P12V_E1S_0
  18  VOUT_18  OUT  = P12V_E1S_0
  19  VOUT_19  OUT  = P12V_E1S_0
  20  VOUT_20  OUT  = P12V_E1S_0
  21_22  VIN_21_22  IN  = P12V_AUX
  23  VIN_23  IN  = P12V_AUX
  24  VIN_24  IN  = P12V_AUX
  25  VIN_25  IN  = P12V_AUX
  26  VIN_26  IN  = P12V_AUX

PU293  MP5016GQHLZ  MP5016GQH-L-Z EMPTY  pkg QFN8_2X1-5  page 193
  1_2  VCC  POWER  = P3V3_AUX
  3  GND  POWER  = GND
  4  ILIMIT  OUT  = P3V3_E1S_ILIMIT_0
  5  MODE  IN  = P3V3_E1S_MODE_0
  6_7  SOURCE  OUT  = P3V3_E1S_0_R
  8  GATE  OUT  = P3V3_E1S_GATE_0_PU293
  9  EN  IN  = P3V3_E1S_EN_0_R2
  10  DV_DT  OUT  = P3V3_E1S_DVDT_0

PU294  MAX15090BEWIT  MAX15090BEWI+T EMPTY  pkg BGA28_0-5_3-525X2-065  page 192
  A1  ISENSE  OUT  = P12V_E1S_SENSE_0
  A2  VCC  POWER  = P12V_E1S_VCC_0
  A3  IN_A3  IN  = P12V_AUX
  A4  OUT_A4  OUT  = P12V_E1S_0
  A5  IN_A5  IN  = P12V_AUX
  A6  GATE  BI  = P12V_E1S_GATE_0
  A7  CDLY  IN  = GND
  B1  CB  BI  = P12V_E1S_CB_0
  B2  GND_B2  POWER  = GND
  B3  IN_B3  IN  = P12V_AUX
  B4  OUT_B4  OUT  = P12V_E1S_0
  B5  IN_B5  IN  = P12V_AUX
  B6  OUT_B6  OUT  = P12V_E1S_0
  B7  \en#\  IN  = GND
  C1  GND_C1  POWER  = GND
  C2  GND_C2  POWER  = GND
  C3  IN_C3  IN  = P12V_AUX
  C4  OUT_C4  OUT  = P12V_E1S_0
  C5  IN_C5  IN  = P12V_AUX
  C6  OUT_C6  OUT  = P12V_E1S_0
  C7  \fault#\  OUT  = P12V_E1S_FAULT_0
  D1  REG  OUT  = P12V_E1S_REG_0
  D2  UV  IN  = P12V_E1S_UV_0
  D3  OV  IN  = P12V_E1S_OV_0
  D4  OUT_D4  OUT  = P12V_E1S_0
  D5  IN_D5  IN  = P12V_AUX
  D6  OUT_D6  OUT  = P12V_E1S_0
  D7  PG  OUT  = P12V_E1S_PWRGD_0

PU295  MAX15090BEWIT  MAX15090BEWI+T IC  pkg BGA28_0-5_3-525X2-065  page 192
  A1  ISENSE  OUT  = P3V3_E1S_SENSE_0
  A2  VCC  POWER  = P3V3_E1S_VCC_0
  A3  IN_A3  IN  = P3V3_AUX
  A4  OUT_A4  OUT  = P3V3_E1S_0_R
  A5  IN_A5  IN  = P3V3_AUX
  A6  GATE  BI  = P3V3_E1S_GATE_0
  A7  CDLY  IN  = GND
  B1  CB  BI  = P3V3_E1S_CB_0
  B2  GND_B2  POWER  = GND
  B3  IN_B3  IN  = P3V3_AUX
  B4  OUT_B4  OUT  = P3V3_E1S_0_R
  B5  IN_B5  IN  = P3V3_AUX
  B6  OUT_B6  OUT  = P3V3_E1S_0_R
  B7  \en#\  IN  = GND
  C1  GND_C1  POWER  = GND
  C2  GND_C2  POWER  = GND
  C3  IN_C3  IN  = P3V3_AUX
  C4  OUT_C4  OUT  = P3V3_E1S_0_R
  C5  IN_C5  IN  = P3V3_AUX
  C6  OUT_C6  OUT  = P3V3_E1S_0_R
  C7  \fault#\  OUT  = P3V3_E1S_FAULT_0
  D1  REG  OUT  = P3V3_E1S_REG_0
  D2  UV  IN  = P3V3_E1S_UV_0
  D3  OV  IN  = P3V3_E1S_OV_0
  D4  OUT_D4  OUT  = P3V3_E1S_0_R
  D5  IN_D5  IN  = P3V3_AUX
  D6  OUT_D6  OUT  = P3V3_E1S_0_R
  D7  PG  OUT  = P3V3_E1S_PWRGD_0

PU296  MP5991GLUZ  MP5991GLU-Z IC  pkg LGA32_TH_0-5_5X5  page 303
  1  VOUT1  OUT  = P12V_AUX
  2  VOUT2  OUT  = P12V_AUX
  3  D_OC  OUT  = HSC_D_OC_3
  4  \on\  IN  = HSC_ON
  5  GOK  OUT  = HSC_FAULT
  6  FLT_TYPE  IN  = HSC_FLT_TYPE_3
  7  NC1  TRI  = HSC_NC1_3
  8  MODE  IN  = HSC_MODE_3
  9  VIN1  IN  = P12V_PSU
  10  VIN2  IN  = P12V_PSU
  11  VIN3  IN  = P12V_PSU
  12  VIN4  IN  = P12V_PSU
  13  VIN5  IN  = P12V_PSU
  14  VIN6  IN  = P12V_PSU
  15  VIN7  IN  = P12V_PSU
  16  VIN8  IN  = P12V_PSU
  17  SCREF_OCWREF  IN  = HSC_SCREF_3
  18  VTEMP  OUT  = HSC_VTEMP
  19  SS  IN  = HSC_SS
  20  GND  POWER  = AGND_HSC
  21  VDD33  POWER  = HSC_VDD_R_3
  22  IMON  OUT  = HSC_IMON
  23  CS  OUT  = HSC_CS_3
  24  OCREF  OUT  = HSC_OCREF
  25  VOUT3  OUT  = P12V_AUX
  26  VOUT4  OUT  = P12V_AUX
  27  VOUT5  OUT  = P12V_AUX
  28  VOUT6  OUT  = P12V_AUX
  29  VOUT7  OUT  = P12V_AUX
  30  VOUT8  OUT  = P12V_AUX
  31  VOUT9  OUT  = P12V_AUX
  32  VOUT10  OUT  = P12V_AUX
  33  VIN9  IN  = P12V_PSU

PU297  MP5991GLUZ  MP5991GLU-Z IC  pkg LGA32_TH_0-5_5X5  page 303
  1  VOUT1  OUT  = P12V_AUX
  2  VOUT2  OUT  = P12V_AUX
  3  D_OC  OUT  = HSC_D_OC_4
  4  \on\  IN  = HSC_ON
  5  GOK  OUT  = HSC_FAULT
  6  FLT_TYPE  IN  = HSC_FLT_TYPE_4
  7  NC1  TRI  = HSC_NC1_4
  8  MODE  IN  = HSC_MODE_4
  9  VIN1  IN  = P12V_PSU
  10  VIN2  IN  = P12V_PSU
  11  VIN3  IN  = P12V_PSU
  12  VIN4  IN  = P12V_PSU
  13  VIN5  IN  = P12V_PSU
  14  VIN6  IN  = P12V_PSU
  15  VIN7  IN  = P12V_PSU
  16  VIN8  IN  = P12V_PSU
  17  SCREF_OCWREF  IN  = HSC_SCREF_4
  18  VTEMP  OUT  = HSC_VTEMP
  19  SS  IN  = HSC_SS
  20  GND  POWER  = AGND_HSC
  21  VDD33  POWER  = HSC_VDD_R_4
  22  IMON  OUT  = HSC_IMON
  23  CS  OUT  = HSC_CS_4
  24  OCREF  OUT  = HSC_OCREF
  25  VOUT3  OUT  = P12V_AUX
  26  VOUT4  OUT  = P12V_AUX
  27  VOUT5  OUT  = P12V_AUX
  28  VOUT6  OUT  = P12V_AUX
  29  VOUT7  OUT  = P12V_AUX
  30  VOUT8  OUT  = P12V_AUX
  31  VOUT9  OUT  = P12V_AUX
  32  VOUT10  OUT  = P12V_AUX
  33  VIN9  IN  = P12V_PSU

PU299  RS31312R  IC  pkg QFN22_TH_3X5  page 242
  1  EN  IN  = P12V_SCM_EN_R2
  2  LOADEN  IN  = GND
  3  ENTM  IN  = GND
  4  TIMER  IN  = P12V_SCM_TIMER
  5  ISET  IN  = P12V_SCM_ISET
  6  SS  IN  = P12V_SCM_SS
  7  GND  POWER  = GND
  8  IMON  OUT  = P12V_SCM_IMON
  9  FLTB  OUT  = P12V_SCM_FLTB_N
  10  PG  OUT  = HP_LVC3_SCM_HSC_PWRGD_R
  11  OV  IN  = P12V_SCM_OV_FB
  12  AVIN  IN  = P12V_SCM_AVIN_PD
  13  VOUT_13  OUT  = P12V_SCM_R
  14  VOUT_14  OUT  = P12V_SCM_R
  15  VOUT_15  OUT  = P12V_SCM_R
  16  VOUT_16  OUT  = P12V_SCM_R
  17  VOUT_17  OUT  = P12V_SCM_R
  18  VOUT_18  OUT  = P12V_SCM_R
  19  VOUT_19  OUT  = P12V_SCM_R
  20  VOUT_20  OUT  = P12V_SCM_R
  21_22  VIN_21_22  IN  = P12V_AUX
  23  VIN_23  IN  = P12V_AUX
  24  VIN_24  IN  = P12V_AUX
  25  VIN_25  IN  = P12V_AUX
  26  VIN_26  IN  = P12V_AUX

PU300  MAX15090BEWIT  MAX15090BEWI+T EMPTY  pkg BGA28_0-5_3-525X2-065  page 242
  A1  ISENSE  OUT  = P12V_SCM_SENSE
  A2  VCC  POWER  = P12V_SCM_VCC
  A3  IN_A3  IN  = P12V_AUX
  A4  OUT_A4  OUT  = P12V_SCM_R
  A5  IN_A5  IN  = P12V_AUX
  A6  GATE  BI  = P12V_SCM_GATE
  A7  CDLY  IN  = GND
  B1  CB  BI  = P12V_SCM_CB
  B2  GND_B2  POWER  = GND
  B3  IN_B3  IN  = P12V_AUX
  B4  OUT_B4  OUT  = P12V_SCM_R
  B5  IN_B5  IN  = P12V_AUX
  B6  OUT_B6  OUT  = P12V_SCM_R
  B7  \en#\  IN  = GND
  C1  GND_C1  POWER  = GND
  C2  GND_C2  POWER  = GND
  C3  IN_C3  IN  = P12V_AUX
  C4  OUT_C4  OUT  = P12V_SCM_R
  C5  IN_C5  IN  = P12V_AUX
  C6  OUT_C6  OUT  = P12V_SCM_R
  C7  \fault#\  OUT  = P12V_SCM_FAULT_N
  D1  REG  OUT  = P12V_SCM_REG
  D2  UV  IN  = P12V_SCM_UV
  D3  OV  IN  = P12V_SCM_OV
  D4  OUT_D4  OUT  = P12V_SCM_R
  D5  IN_D5  IN  = P12V_AUX
  D6  OUT_D6  OUT  = P12V_SCM_R
  D7  PG  OUT  = P12V_SCM_PWRGD

Q15  MOSFET_NCH_DUAL  PJT138K IC  pkg SOT363XD  page 235
  1  S1  BI  = GND
  2  G1  BI  = FM_SMB_PEHPCPU0_PCIE_ALERT_R_N
  3  D2  BI  = FM_PEHPCPU0_ALERT_N
  4  S2  BI  = GND
  5  G2  BI  = FM_SMB_CPU0_ALERT_R1
  6  D1  BI  = FM_SMB_CPU0_ALERT_R1
